(kicad_pcb
	(version 20260206)
	(generator "pcbnew")
	(generator_version "10.0")
	(general
		(thickness 1.6)
		(legacy_teardrops no)
	)
	(paper "A4")
	(title_block
		(title "01162023_DA0F0TEBIF0_F0T_Expander_BD_F_brd_V02_OCP.brd")
		(comment 1 "Grand Teton / footprints 262-268 of 9728")
	)
	(layers
		(0 "F.Cu" signal "TOP")
		(4 "In1.Cu" signal "GND")
		(6 "In2.Cu" signal "VCC")
		(8 "In3.Cu" signal "VCC1")
		(10 "In4.Cu" signal "GND1")
		(12 "In5.Cu" signal "IN1")
		(14 "In6.Cu" signal "GND2")
		(16 "In7.Cu" signal "IN2")
		(18 "In8.Cu" signal "GND3")
		(20 "In9.Cu" signal "IN3")
		(22 "In10.Cu" signal "GND4")
		(24 "In11.Cu" signal "IN4")
		(26 "In12.Cu" signal "GND5")
		(28 "In13.Cu" signal "IN5")
		(30 "In14.Cu" signal "GND6")
		(32 "In15.Cu" signal "IN6")
		(34 "In16.Cu" signal "GND7")
		(2 "B.Cu" signal "BOTTOM")
		(9 "F.Adhes" user "F.Adhesive")
		(11 "B.Adhes" user "B.Adhesive")
		(13 "F.Paste" user "Package Geometry/Pastemask Top")
		(15 "B.Paste" user "Package Geometry/Pastemask Bottom")
		(5 "F.SilkS" user "Ref Des/Silkscreen Top")
		(7 "B.SilkS" user "Ref Des/Silkscreen Bottom")
		(1 "F.Mask" user "Board Geometry/Soldermask Top")
		(3 "B.Mask" user "Board Geometry/Soldermask Bottom")
		(17 "Dwgs.User" user "User.Drawings")
		(19 "Cmts.User" user "User.Comments")
		(21 "Eco1.User" user "User.Eco1")
		(23 "Eco2.User" user "User.Eco2")
		(25 "Edge.Cuts" user "Board Geometry/Outline")
		(27 "Margin" user)
		(31 "F.CrtYd" user "Package Geometry/Place Bound Top")
		(29 "B.CrtYd" user "Package Geometry/Place Bound Bottom")
		(35 "F.Fab" user "Ref Des/Assembly Top")
		(33 "B.Fab" user "Ref Des/Assembly Bottom")
	)
	(footprint ""
		(layer "F.Cu")
		(at 356.17531 -252.416564 90)
		(property "Reference" "R837"
			(at 0 0 90)
			(layer "F.SilkS")
			(hide yes)
			(effects
				(font
					(size 1.27 1.27)
				)
			)
		)
		(property "Value" ""
			(at 0 0 90)
			(layer "F.Fab")
			(effects
				(font
					(size 1.27 1.27)
				)
			)
		)
		(duplicate_pad_numbers_are_jumpers no)
		(fp_line
			(start 0.7874 -0.4064)
			(end 0.7874 0.4064)
			(stroke
				(width 0.1524)
				(type default)
			)
			(layer "F.SilkS")
		)
		(fp_line
			(start -0.7874 -0.4064)
			(end 0.7874 -0.4064)
			(stroke
				(width 0.1524)
				(type default)
			)
			(layer "F.SilkS")
		)
		(fp_line
			(start 0.7874 0.4064)
			(end -0.7874 0.4064)
			(stroke
				(width 0.1524)
				(type default)
			)
			(layer "F.SilkS")
		)
		(fp_line
			(start -0.7874 0.4064)
			(end -0.7874 -0.4064)
			(stroke
				(width 0.1524)
				(type default)
			)
			(layer "F.SilkS")
		)
		(fp_line
			(start -0.12065 -0.305054)
			(end -0.12065 -0.2794)
			(stroke
				(width 0.1)
				(type default)
			)
			(layer "F.Fab")
		)
		(fp_line
			(start -0.67945 -0.305054)
			(end -0.12065 -0.305054)
			(stroke
				(width 0.1)
				(type default)
			)
			(layer "F.Fab")
		)
		(fp_line
			(start 0.67945 -0.3048)
			(end 0.67945 0.3048)
			(stroke
				(width 0.1)
				(type default)
			)
			(layer "F.Fab")
		)
		(fp_line
			(start 0.12065 -0.3048)
			(end 0.67945 -0.3048)
			(stroke
				(width 0.1)
				(type default)
			)
			(layer "F.Fab")
		)
		(fp_line
			(start 0.12065 -0.2794)
			(end 0.12065 -0.3048)
			(stroke
				(width 0.1)
				(type default)
			)
			(layer "F.Fab")
		)
		(fp_line
			(start -0.12065 -0.2794)
			(end 0.12065 -0.2794)
			(stroke
				(width 0.1)
				(type default)
			)
			(layer "F.Fab")
		)
		(fp_line
			(start 0.120396 0.2794)
			(end -0.12065 0.2794)
			(stroke
				(width 0.1)
				(type default)
			)
			(layer "F.Fab")
		)
		(fp_line
			(start -0.12065 0.2794)
			(end -0.12065 0.3048)
			(stroke
				(width 0.1)
				(type default)
			)
			(layer "F.Fab")
		)
		(fp_line
			(start 0.67945 0.3048)
			(end 0.120396 0.3048)
			(stroke
				(width 0.1)
				(type default)
			)
			(layer "F.Fab")
		)
		(fp_line
			(start 0.120396 0.3048)
			(end 0.120396 0.2794)
			(stroke
				(width 0.1)
				(type default)
			)
			(layer "F.Fab")
		)
		(fp_line
			(start -0.12065 0.3048)
			(end -0.67945 0.3048)
			(stroke
				(width 0.1)
				(type default)
			)
			(layer "F.Fab")
		)
		(fp_line
			(start -0.67945 0.3048)
			(end -0.67945 -0.305054)
			(stroke
				(width 0.1)
				(type default)
			)
			(layer "F.Fab")
		)
		(pad "1" smd circle
			(at -0.40005 0 90)
			(size 0 0)
			(layers "F.Cu" "F.Mask" "F.Paste")
			(net "SMB_BIC_I2C6_MUX_VR_R_SDA")
		)
		(pad "2" smd circle
			(at 0.40005 0 90)
			(size 0 0)
			(layers "F.Cu" "F.Mask" "F.Paste")
			(net "SMB_VR_P0V8_PEX2_SDA")
		)
	)
	(footprint ""
		(layer "F.Cu")
		(at 102.987094 -397.512286 90)
		(property "Reference" "R5443"
			(at 0 0 90)
			(layer "F.SilkS")
			(hide yes)
			(effects
				(font
					(size 1.27 1.27)
				)
			)
		)
		(property "Value" ""
			(at 0 0 90)
			(layer "F.Fab")
			(effects
				(font
					(size 1.27 1.27)
				)
			)
		)
		(duplicate_pad_numbers_are_jumpers no)
		(fp_line
			(start 0.7874 -0.4064)
			(end 0.7874 0.4064)
			(stroke
				(width 0.1524)
				(type default)
			)
			(layer "F.SilkS")
		)
		(fp_line
			(start -0.7874 -0.4064)
			(end 0.7874 -0.4064)
			(stroke
				(width 0.1524)
				(type default)
			)
			(layer "F.SilkS")
		)
		(fp_line
			(start 0.7874 0.4064)
			(end -0.7874 0.4064)
			(stroke
				(width 0.1524)
				(type default)
			)
			(layer "F.SilkS")
		)
		(fp_line
			(start -0.7874 0.4064)
			(end -0.7874 -0.4064)
			(stroke
				(width 0.1524)
				(type default)
			)
			(layer "F.SilkS")
		)
		(fp_line
			(start -0.12065 -0.305054)
			(end -0.12065 -0.2794)
			(stroke
				(width 0.1)
				(type default)
			)
			(layer "F.Fab")
		)
		(fp_line
			(start -0.67945 -0.305054)
			(end -0.12065 -0.305054)
			(stroke
				(width 0.1)
				(type default)
			)
			(layer "F.Fab")
		)
		(fp_line
			(start 0.67945 -0.3048)
			(end 0.67945 0.3048)
			(stroke
				(width 0.1)
				(type default)
			)
			(layer "F.Fab")
		)
		(fp_line
			(start 0.12065 -0.3048)
			(end 0.67945 -0.3048)
			(stroke
				(width 0.1)
				(type default)
			)
			(layer "F.Fab")
		)
		(fp_line
			(start 0.12065 -0.2794)
			(end 0.12065 -0.3048)
			(stroke
				(width 0.1)
				(type default)
			)
			(layer "F.Fab")
		)
		(fp_line
			(start -0.12065 -0.2794)
			(end 0.12065 -0.2794)
			(stroke
				(width 0.1)
				(type default)
			)
			(layer "F.Fab")
		)
		(fp_line
			(start 0.120396 0.2794)
			(end -0.12065 0.2794)
			(stroke
				(width 0.1)
				(type default)
			)
			(layer "F.Fab")
		)
		(fp_line
			(start -0.12065 0.2794)
			(end -0.12065 0.3048)
			(stroke
				(width 0.1)
				(type default)
			)
			(layer "F.Fab")
		)
		(fp_line
			(start 0.67945 0.3048)
			(end 0.120396 0.3048)
			(stroke
				(width 0.1)
				(type default)
			)
			(layer "F.Fab")
		)
		(fp_line
			(start 0.120396 0.3048)
			(end 0.120396 0.2794)
			(stroke
				(width 0.1)
				(type default)
			)
			(layer "F.Fab")
		)
		(fp_line
			(start -0.12065 0.3048)
			(end -0.67945 0.3048)
			(stroke
				(width 0.1)
				(type default)
			)
			(layer "F.Fab")
		)
		(fp_line
			(start -0.67945 0.3048)
			(end -0.67945 -0.305054)
			(stroke
				(width 0.1)
				(type default)
			)
			(layer "F.Fab")
		)
		(pad "1" smd circle
			(at -0.40005 0 90)
			(size 0 0)
			(layers "F.Cu" "F.Mask" "F.Paste")
			(net "BIC_USB_HUB_TEST")
		)
		(pad "2" smd circle
			(at 0.40005 0 90)
			(size 0 0)
			(layers "F.Cu" "F.Mask" "F.Paste")
			(net "GND")
		)
	)
	(footprint ""
		(layer "F.Cu")
		(at 184.491884 -196.122798 180)
		(property "Reference" "R469"
			(at 0 0 180)
			(layer "F.SilkS")
			(hide yes)
			(effects
				(font
					(size 1.27 1.27)
				)
			)
		)
		(property "Value" ""
			(at 0 0 180)
			(layer "F.Fab")
			(effects
				(font
					(size 1.27 1.27)
				)
			)
		)
		(duplicate_pad_numbers_are_jumpers no)
		(fp_line
			(start 0.7874 0.4064)
			(end -0.7874 0.4064)
			(stroke
				(width 0.1524)
				(type default)
			)
			(layer "F.SilkS")
		)
		(fp_line
			(start 0.7874 -0.4064)
			(end 0.7874 0.4064)
			(stroke
				(width 0.1524)
				(type default)
			)
			(layer "F.SilkS")
		)
		(fp_line
			(start -0.7874 0.4064)
			(end -0.7874 -0.4064)
			(stroke
				(width 0.1524)
				(type default)
			)
			(layer "F.SilkS")
		)
		(fp_line
			(start -0.7874 -0.4064)
			(end 0.7874 -0.4064)
			(stroke
				(width 0.1524)
				(type default)
			)
			(layer "F.SilkS")
		)
		(fp_line
			(start 0.67945 0.3048)
			(end 0.120396 0.3048)
			(stroke
				(width 0.1)
				(type default)
			)
			(layer "F.Fab")
		)
		(fp_line
			(start 0.67945 -0.3048)
			(end 0.67945 0.3048)
			(stroke
				(width 0.1)
				(type default)
			)
			(layer "F.Fab")
		)
		(fp_line
			(start 0.12065 -0.2794)
			(end 0.12065 -0.3048)
			(stroke
				(width 0.1)
				(type default)
			)
			(layer "F.Fab")
		)
		(fp_line
			(start 0.12065 -0.3048)
			(end 0.67945 -0.3048)
			(stroke
				(width 0.1)
				(type default)
			)
			(layer "F.Fab")
		)
		(fp_line
			(start 0.120396 0.3048)
			(end 0.120396 0.2794)
			(stroke
				(width 0.1)
				(type default)
			)
			(layer "F.Fab")
		)
		(fp_line
			(start 0.120396 0.2794)
			(end -0.12065 0.2794)
			(stroke
				(width 0.1)
				(type default)
			)
			(layer "F.Fab")
		)
		(fp_line
			(start -0.12065 0.3048)
			(end -0.67945 0.3048)
			(stroke
				(width 0.1)
				(type default)
			)
			(layer "F.Fab")
		)
		(fp_line
			(start -0.12065 0.2794)
			(end -0.12065 0.3048)
			(stroke
				(width 0.1)
				(type default)
			)
			(layer "F.Fab")
		)
		(fp_line
			(start -0.12065 -0.2794)
			(end 0.12065 -0.2794)
			(stroke
				(width 0.1)
				(type default)
			)
			(layer "F.Fab")
		)
		(fp_line
			(start -0.12065 -0.305054)
			(end -0.12065 -0.2794)
			(stroke
				(width 0.1)
				(type default)
			)
			(layer "F.Fab")
		)
		(fp_line
			(start -0.67945 0.3048)
			(end -0.67945 -0.305054)
			(stroke
				(width 0.1)
				(type default)
			)
			(layer "F.Fab")
		)
		(fp_line
			(start -0.67945 -0.305054)
			(end -0.12065 -0.305054)
			(stroke
				(width 0.1)
				(type default)
			)
			(layer "F.Fab")
		)
		(pad "1" smd circle
			(at -0.40005 0 180)
			(size 0 0)
			(layers "F.Cu" "F.Mask" "F.Paste")
			(net "SPI_BIC1_CS0_R1_N")
		)
		(pad "2" smd circle
			(at 0.40005 0 180)
			(size 0 0)
			(layers "F.Cu" "F.Mask" "F.Paste")
			(net "SPI_BIC1_CS0_R2_N")
		)
	)
	(footprint ""
		(layer "F.Cu")
		(at 193.250312 -343.952322 90)
		(property "Reference" "C372"
			(at 0 0 90)
			(layer "F.SilkS")
			(hide yes)
			(effects
				(font
					(size 1.27 1.27)
				)
			)
		)
		(property "Value" ""
			(at 0 0 90)
			(layer "F.Fab")
			(effects
				(font
					(size 1.27 1.27)
				)
			)
		)
		(duplicate_pad_numbers_are_jumpers no)
		(fp_line
			(start 0.299974 -0.150114)
			(end 0.299974 0.150114)
			(stroke
				(width 0.1)
				(type default)
			)
			(layer "F.Fab")
		)
		(fp_line
			(start -0.299974 -0.150114)
			(end 0.299974 -0.150114)
			(stroke
				(width 0.1)
				(type default)
			)
			(layer "F.Fab")
		)
		(fp_line
			(start 0.299974 0.150114)
			(end -0.299974 0.150114)
			(stroke
				(width 0.1)
				(type default)
			)
			(layer "F.Fab")
		)
		(fp_line
			(start -0.299974 0.150114)
			(end -0.299974 -0.150114)
			(stroke
				(width 0.1)
				(type default)
			)
			(layer "F.Fab")
		)
		(pad "1" smd rect
			(at -0.2667 0 90)
			(size 0.3048 0.381)
			(layers "F.Cu" "F.Mask" "F.Paste")
			(net "P5E_PEX1_STN7_TX_DP<127>")
		)
		(pad "2" smd rect
			(at 0.2667 0 90)
			(size 0.3048 0.381)
			(layers "F.Cu" "F.Mask" "F.Paste")
			(net "P5E_PEX1_STN7_TX_C_DP<127>")
		)
	)
	(footprint ""
		(layer "F.Cu")
		(at 129.217166 -118.343426 90)
		(property "Reference" "R5964"
			(at 0 0 90)
			(layer "F.SilkS")
			(hide yes)
			(effects
				(font
					(size 1.27 1.27)
				)
			)
		)
		(property "Value" ""
			(at 0 0 90)
			(layer "F.Fab")
			(effects
				(font
					(size 1.27 1.27)
				)
			)
		)
		(duplicate_pad_numbers_are_jumpers no)
		(fp_line
			(start 0.7874 -0.4064)
			(end 0.7874 0.4064)
			(stroke
				(width 0.1524)
				(type default)
			)
			(layer "F.SilkS")
		)
		(fp_line
			(start -0.7874 -0.4064)
			(end 0.7874 -0.4064)
			(stroke
				(width 0.1524)
				(type default)
			)
			(layer "F.SilkS")
		)
		(fp_line
			(start 0.7874 0.4064)
			(end -0.7874 0.4064)
			(stroke
				(width 0.1524)
				(type default)
			)
			(layer "F.SilkS")
		)
		(fp_line
			(start -0.7874 0.4064)
			(end -0.7874 -0.4064)
			(stroke
				(width 0.1524)
				(type default)
			)
			(layer "F.SilkS")
		)
		(fp_line
			(start -0.12065 -0.305054)
			(end -0.12065 -0.2794)
			(stroke
				(width 0.1)
				(type default)
			)
			(layer "F.Fab")
		)
		(fp_line
			(start -0.67945 -0.305054)
			(end -0.12065 -0.305054)
			(stroke
				(width 0.1)
				(type default)
			)
			(layer "F.Fab")
		)
		(fp_line
			(start 0.67945 -0.3048)
			(end 0.67945 0.3048)
			(stroke
				(width 0.1)
				(type default)
			)
			(layer "F.Fab")
		)
		(fp_line
			(start 0.12065 -0.3048)
			(end 0.67945 -0.3048)
			(stroke
				(width 0.1)
				(type default)
			)
			(layer "F.Fab")
		)
		(fp_line
			(start 0.12065 -0.2794)
			(end 0.12065 -0.3048)
			(stroke
				(width 0.1)
				(type default)
			)
			(layer "F.Fab")
		)
		(fp_line
			(start -0.12065 -0.2794)
			(end 0.12065 -0.2794)
			(stroke
				(width 0.1)
				(type default)
			)
			(layer "F.Fab")
		)
		(fp_line
			(start 0.120396 0.2794)
			(end -0.12065 0.2794)
			(stroke
				(width 0.1)
				(type default)
			)
			(layer "F.Fab")
		)
		(fp_line
			(start -0.12065 0.2794)
			(end -0.12065 0.3048)
			(stroke
				(width 0.1)
				(type default)
			)
			(layer "F.Fab")
		)
		(fp_line
			(start 0.67945 0.3048)
			(end 0.120396 0.3048)
			(stroke
				(width 0.1)
				(type default)
			)
			(layer "F.Fab")
		)
		(fp_line
			(start 0.120396 0.3048)
			(end 0.120396 0.2794)
			(stroke
				(width 0.1)
				(type default)
			)
			(layer "F.Fab")
		)
		(fp_line
			(start -0.12065 0.3048)
			(end -0.67945 0.3048)
			(stroke
				(width 0.1)
				(type default)
			)
			(layer "F.Fab")
		)
		(fp_line
			(start -0.67945 0.3048)
			(end -0.67945 -0.305054)
			(stroke
				(width 0.1)
				(type default)
			)
			(layer "F.Fab")
		)
		(pad "1" smd circle
			(at -0.40005 0 90)
			(size 0 0)
			(layers "F.Cu" "F.Mask" "F.Paste")
			(net "P3V3_NIC2_PG_G1")
		)
		(pad "2" smd circle
			(at 0.40005 0 90)
			(size 0 0)
			(layers "F.Cu" "F.Mask" "F.Paste")
			(net "GND")
		)
	)
	(footprint ""
		(layer "F.Cu")
		(at 31.86684 -52.543456 180)
		(property "Reference" "PC512"
			(at 0 0 180)
			(layer "F.SilkS")
			(hide yes)
			(effects
				(font
					(size 1.27 1.27)
				)
			)
		)
		(property "Value" ""
			(at 0 0 180)
			(layer "F.Fab")
			(effects
				(font
					(size 1.27 1.27)
				)
			)
		)
		(duplicate_pad_numbers_are_jumpers no)
		(fp_line
			(start 0.7874 0.4064)
			(end -0.7874 0.4064)
			(stroke
				(width 0.1524)
				(type default)
			)
			(layer "F.SilkS")
		)
		(fp_line
			(start 0.7874 -0.4064)
			(end 0.7874 0.4064)
			(stroke
				(width 0.1524)
				(type default)
			)
			(layer "F.SilkS")
		)
		(fp_line
			(start -0.7874 0.4064)
			(end -0.7874 -0.4064)
			(stroke
				(width 0.1524)
				(type default)
			)
			(layer "F.SilkS")
		)
		(fp_line
			(start -0.7874 -0.4064)
			(end 0.7874 -0.4064)
			(stroke
				(width 0.1524)
				(type default)
			)
			(layer "F.SilkS")
		)
		(fp_line
			(start 0.67945 0.3048)
			(end 0.120396 0.3048)
			(stroke
				(width 0.1)
				(type default)
			)
			(layer "F.Fab")
		)
		(fp_line
			(start 0.67945 -0.3048)
			(end 0.67945 0.3048)
			(stroke
				(width 0.1)
				(type default)
			)
			(layer "F.Fab")
		)
		(fp_line
			(start 0.12065 -0.2794)
			(end 0.12065 -0.3048)
			(stroke
				(width 0.1)
				(type default)
			)
			(layer "F.Fab")
		)
		(fp_line
			(start 0.12065 -0.3048)
			(end 0.67945 -0.3048)
			(stroke
				(width 0.1)
				(type default)
			)
			(layer "F.Fab")
		)
		(fp_line
			(start 0.120396 0.3048)
			(end 0.120396 0.2794)
			(stroke
				(width 0.1)
				(type default)
			)
			(layer "F.Fab")
		)
		(fp_line
			(start 0.120396 0.2794)
			(end -0.12065 0.2794)
			(stroke
				(width 0.1)
				(type default)
			)
			(layer "F.Fab")
		)
		(fp_line
			(start -0.12065 0.3048)
			(end -0.67945 0.3048)
			(stroke
				(width 0.1)
				(type default)
			)
			(layer "F.Fab")
		)
		(fp_line
			(start -0.12065 0.2794)
			(end -0.12065 0.3048)
			(stroke
				(width 0.1)
				(type default)
			)
			(layer "F.Fab")
		)
		(fp_line
			(start -0.12065 -0.2794)
			(end 0.12065 -0.2794)
			(stroke
				(width 0.1)
				(type default)
			)
			(layer "F.Fab")
		)
		(fp_line
			(start -0.12065 -0.305054)
			(end -0.12065 -0.2794)
			(stroke
				(width 0.1)
				(type default)
			)
			(layer "F.Fab")
		)
		(fp_line
			(start -0.67945 0.3048)
			(end -0.67945 -0.305054)
			(stroke
				(width 0.1)
				(type default)
			)
			(layer "F.Fab")
		)
		(fp_line
			(start -0.67945 -0.305054)
			(end -0.12065 -0.305054)
			(stroke
				(width 0.1)
				(type default)
			)
			(layer "F.Fab")
		)
		(pad "1" smd circle
			(at -0.40005 0 180)
			(size 0 0)
			(layers "F.Cu" "F.Mask" "F.Paste")
			(net "P3V3_SSD1")
		)
		(pad "2" smd circle
			(at 0.40005 0 180)
			(size 0 0)
			(layers "F.Cu" "F.Mask" "F.Paste")
			(net "GND")
		)
	)
	(footprint ""
		(layer "F.Cu")
		(at 98.434398 -34.546286 180)
		(property "Reference" "C89"
			(at 0 0 180)
			(layer "F.SilkS")
			(hide yes)
			(effects
				(font
					(size 1.27 1.27)
				)
			)
		)
		(property "Value" ""
			(at 0 0 180)
			(layer "F.Fab")
			(effects
				(font
					(size 1.27 1.27)
				)
			)
		)
		(duplicate_pad_numbers_are_jumpers no)
		(fp_line
			(start 0.299974 0.150114)
			(end -0.299974 0.150114)
			(stroke
				(width 0.1)
				(type default)
			)
			(layer "F.Fab")
		)
		(fp_line
			(start 0.299974 -0.150114)
			(end 0.299974 0.150114)
			(stroke
				(width 0.1)
				(type default)
			)
			(layer "F.Fab")
		)
		(fp_line
			(start -0.299974 0.150114)
			(end -0.299974 -0.150114)
			(stroke
				(width 0.1)
				(type default)
			)
			(layer "F.Fab")
		)
		(fp_line
			(start -0.299974 -0.150114)
			(end 0.299974 -0.150114)
			(stroke
				(width 0.1)
				(type default)
			)
			(layer "F.Fab")
		)
		(pad "1" smd rect
			(at -0.2667 0 180)
			(size 0.3048 0.381)
			(layers "F.Cu" "F.Mask" "F.Paste")
			(net "P5E_PEX0_STN2_TX_DP<35>")
		)
		(pad "2" smd rect
			(at 0.2667 0 180)
			(size 0.3048 0.381)
			(layers "F.Cu" "F.Mask" "F.Paste")
			(net "P5E_PEX0_STN2_TX_C_DP<35>")
		)
	)
)
